(kicad_pcb
	(version 20260206)
	(generator "pcbnew")
	(generator_version "10.0")
	(general
		(thickness 1.6)
		(legacy_teardrops no)
	)
	(paper "A4")
	(title_block
		(title "01162023_DA0F0TEBIF0_F0T_Expander_BD_F_brd_V02_OCP.brd")
		(comment 1 "Grand Teton / footprint 1849 of 9728 (U5), pads 1-110 of 256")
	)
	(layers
		(0 "F.Cu" signal "TOP")
		(4 "In1.Cu" signal "GND")
		(6 "In2.Cu" signal "VCC")
		(8 "In3.Cu" signal "VCC1")
		(10 "In4.Cu" signal "GND1")
		(12 "In5.Cu" signal "IN1")
		(14 "In6.Cu" signal "GND2")
		(16 "In7.Cu" signal "IN2")
		(18 "In8.Cu" signal "GND3")
		(20 "In9.Cu" signal "IN3")
		(22 "In10.Cu" signal "GND4")
		(24 "In11.Cu" signal "IN4")
		(26 "In12.Cu" signal "GND5")
		(28 "In13.Cu" signal "IN5")
		(30 "In14.Cu" signal "GND6")
		(32 "In15.Cu" signal "IN6")
		(34 "In16.Cu" signal "GND7")
		(2 "B.Cu" signal "BOTTOM")
		(9 "F.Adhes" user "F.Adhesive")
		(11 "B.Adhes" user "B.Adhesive")
		(13 "F.Paste" user "Package Geometry/Pastemask Top")
		(15 "B.Paste" user "Package Geometry/Pastemask Bottom")
		(5 "F.SilkS" user "Ref Des/Silkscreen Top")
		(7 "B.SilkS" user "Ref Des/Silkscreen Bottom")
		(1 "F.Mask" user "Board Geometry/Soldermask Top")
		(3 "B.Mask" user "Board Geometry/Soldermask Bottom")
		(17 "Dwgs.User" user "User.Drawings")
		(19 "Cmts.User" user "User.Comments")
		(21 "Eco1.User" user "User.Eco1")
		(23 "Eco2.User" user "User.Eco2")
		(25 "Edge.Cuts" user "Board Geometry/Outline")
		(27 "Margin" user)
		(31 "F.CrtYd" user "Package Geometry/Place Bound Top")
		(29 "B.CrtYd" user "Package Geometry/Place Bound Bottom")
		(35 "F.Fab" user "Ref Des/Assembly Top")
		(33 "B.Fab" user "Ref Des/Assembly Bottom")
	)
	(footprint ""
		(layer "F.Cu")
		(at 229.467664 -218.70416 180)
		(property "Reference" "U5"
			(at -4.517136 -8.03783 0)
			(unlocked yes)
			(layer "F.SilkS")
			(effects
				(font
					(size 0.7874 0.5842)
					(thickness 0.1524)
				)
				(justify left)
			)
		)
		(property "Value" ""
			(at 0 0 180)
			(layer "F.Fab")
			(effects
				(font
					(size 1.27 1.27)
				)
			)
		)
		(duplicate_pad_numbers_are_jumpers no)
		(pad "A1" smd circle
			(at -5.999988 -5.999988 180)
			(size 0.4064 0.4064)
			(layers "F.Cu" "F.Mask" "F.Paste")
			(net "GND")
		)
		(pad "A2" smd circle
			(at -5.199888 -5.999988 180)
			(size 0.4064 0.4064)
			(layers "F.Cu" "F.Mask" "F.Paste")
			(net "BIC_HEARTBEAT_N")
		)
		(pad "A3" smd circle
			(at -4.400042 -5.999988 180)
			(size 0.4064 0.4064)
			(layers "F.Cu" "F.Mask" "F.Paste")
			(net "PD_BIC_ENTEST")
		)
		(pad "A4" smd circle
			(at -3.599942 -5.999988 180)
			(size 0.4064 0.4064)
			(layers "F.Cu" "F.Mask" "F.Paste")
			(net "BIC_SPI1DQ2")
		)
		(pad "A5" smd circle
			(at -2.800096 -5.999988 180)
			(size 0.4064 0.4064)
			(layers "F.Cu" "F.Mask" "F.Paste")
			(net "SPI_BIC1_CLK")
		)
		(pad "A6" smd circle
			(at -1.999996 -5.999988 180)
			(size 0.4064 0.4064)
			(layers "F.Cu" "F.Mask" "F.Paste")
			(net "SPI_BIC1_MOSI")
		)
		(pad "A7" smd circle
			(at -1.199896 -5.999988 180)
			(size 0.4064 0.4064)
			(layers "F.Cu" "F.Mask" "F.Paste")
			(net "SPI_BIC1_CS0_N")
		)
		(pad "A8" smd circle
			(at -0.40005 -5.999988 180)
			(size 0.4064 0.4064)
			(layers "F.Cu" "F.Mask" "F.Paste")
			(net "BIC_SEL_FLASH_SW3")
		)
		(pad "A9" smd circle
			(at 0.40005 -5.999988 180)
			(size 0.4064 0.4064)
			(layers "F.Cu" "F.Mask" "F.Paste")
			(net "SYS_PWR_READY_R_N")
		)
		(pad "A10" smd circle
			(at 1.199896 -5.999988 180)
			(size 0.4064 0.4064)
			(layers "F.Cu" "F.Mask" "F.Paste")
			(net "Net_587")
		)
		(pad "A11" smd circle
			(at 1.999996 -5.999988 180)
			(size 0.4064 0.4064)
			(layers "F.Cu" "F.Mask" "F.Paste")
			(net "JTAG_BIC_TDO_R1")
		)
		(pad "A12" smd circle
			(at 2.800096 -5.999988 180)
			(size 0.4064 0.4064)
			(layers "F.Cu" "F.Mask" "F.Paste")
			(net "JTAG_BIC_NTRST_N")
		)
		(pad "A13" smd circle
			(at 3.599942 -5.999988 180)
			(size 0.4064 0.4064)
			(layers "F.Cu" "F.Mask" "F.Paste")
			(net "RST_SMB_FPGA_N")
		)
		(pad "A14" smd circle
			(at 4.400042 -5.999988 180)
			(size 0.4064 0.4064)
			(layers "F.Cu" "F.Mask" "F.Paste")
			(net "UART_BIC_DEBUG_R_RX")
		)
		(pad "A15" smd circle
			(at 5.199888 -5.999988 180)
			(size 0.4064 0.4064)
			(layers "F.Cu" "F.Mask" "F.Paste")
			(net "MB_BMC_MON_ISO_R")
		)
		(pad "A16" smd circle
			(at 5.999988 -5.999988 180)
			(size 0.4064 0.4064)
			(layers "F.Cu" "F.Mask" "F.Paste")
			(net "PEX_ADC_ALERT_N")
		)
		(pad "B1" smd circle
			(at -5.999988 -5.199888 180)
			(size 0.4064 0.4064)
			(layers "F.Cu" "F.Mask" "F.Paste")
			(net "P5V_AUX_SCALED")
		)
		(pad "B2" smd circle
			(at -5.199888 -5.199888 180)
			(size 0.4064 0.4064)
			(layers "F.Cu" "F.Mask" "F.Paste")
			(net "P12V_AUX_SCALED")
		)
		(pad "B3" smd circle
			(at -4.400042 -5.199888 180)
			(size 0.4064 0.4064)
			(layers "F.Cu" "F.Mask" "F.Paste")
			(net "RST_BIC_EXTRST_N")
		)
		(pad "B4" smd circle
			(at -3.599942 -5.199888 180)
			(size 0.4064 0.4064)
			(layers "F.Cu" "F.Mask" "F.Paste")
			(net "BIC_SPI1DQ3")
		)
		(pad "B5" smd circle
			(at -2.800096 -5.199888 180)
			(size 0.4064 0.4064)
			(layers "F.Cu" "F.Mask" "F.Paste")
			(net "SPI_BIC1_MISO")
		)
		(pad "B6" smd circle
			(at -1.999996 -5.199888 180)
			(size 0.4064 0.4064)
			(layers "F.Cu" "F.Mask" "F.Paste")
			(net "SPI_BIC1_CS1_N")
		)
		(pad "B7" smd circle
			(at -1.199896 -5.199888 180)
			(size 0.4064 0.4064)
			(layers "F.Cu" "F.Mask" "F.Paste")
			(net "GND")
		)
		(pad "B8" smd circle
			(at -0.40005 -5.199888 180)
			(size 0.4064 0.4064)
			(layers "F.Cu" "F.Mask" "F.Paste")
			(net "P3V3_BIC_SPI")
		)
		(pad "B9" smd circle
			(at 0.40005 -5.199888 180)
			(size 0.4064 0.4064)
			(layers "F.Cu" "F.Mask" "F.Paste")
			(net "BIC_SEL_FLASH_SW0")
		)
		(pad "B10" smd circle
			(at 1.199896 -5.199888 180)
			(size 0.4064 0.4064)
			(layers "F.Cu" "F.Mask" "F.Paste")
			(net "BIC_SYS_READY_N")
		)
		(pad "B11" smd circle
			(at 1.999996 -5.199888 180)
			(size 0.4064 0.4064)
			(layers "F.Cu" "F.Mask" "F.Paste")
			(net "JTAG_BIC_TMS")
		)
		(pad "B12" smd circle
			(at 2.800096 -5.199888 180)
			(size 0.4064 0.4064)
			(layers "F.Cu" "F.Mask" "F.Paste")
			(net "RST_SMB_NIC_MUX_N")
		)
		(pad "B13" smd circle
			(at 3.599942 -5.199888 180)
			(size 0.4064 0.4064)
			(layers "F.Cu" "F.Mask" "F.Paste")
			(net "RST_SMB_SSD_N")
		)
		(pad "B14" smd circle
			(at 4.400042 -5.199888 180)
			(size 0.4064 0.4064)
			(layers "F.Cu" "F.Mask" "F.Paste")
			(net "SGPIO_BIC_CLK")
		)
		(pad "B15" smd circle
			(at 5.199888 -5.199888 180)
			(size 0.4064 0.4064)
			(layers "F.Cu" "F.Mask" "F.Paste")
			(net "RST_SSD_LED_IOEXP_N")
		)
		(pad "B16" smd circle
			(at 5.999988 -5.199888 180)
			(size 0.4064 0.4064)
			(layers "F.Cu" "F.Mask" "F.Paste")
			(net "RST_BIC_I2C9_SSD_MUX1_N")
		)
		(pad "C1" smd circle
			(at -5.999988 -4.400042 180)
			(size 0.4064 0.4064)
			(layers "F.Cu" "F.Mask" "F.Paste")
			(net "P3V3_AUX_SCALED")
		)
		(pad "C2" smd circle
			(at -5.199888 -4.400042 180)
			(size 0.4064 0.4064)
			(layers "F.Cu" "F.Mask" "F.Paste")
			(net "P3V3_SCALED")
		)
		(pad "C3" smd circle
			(at -4.400042 -4.400042 180)
			(size 0.4064 0.4064)
			(layers "F.Cu" "F.Mask" "F.Paste")
			(net "RST_BIC_SRST_BIC_N")
		)
		(pad "C4" smd circle
			(at -3.599942 -4.400042 180)
			(size 0.4064 0.4064)
			(layers "F.Cu" "F.Mask" "F.Paste")
			(net "Net_641")
		)
		(pad "C5" smd circle
			(at -2.800096 -4.400042 180)
			(size 0.4064 0.4064)
			(layers "F.Cu" "F.Mask" "F.Paste")
			(net "BIC_FWSPIMOSI")
		)
		(pad "C6" smd circle
			(at -1.999996 -4.400042 180)
			(size 0.4064 0.4064)
			(layers "F.Cu" "F.Mask" "F.Paste")
			(net "GND")
		)
		(pad "C7" smd circle
			(at -1.199896 -4.400042 180)
			(size 0.4064 0.4064)
			(layers "F.Cu" "F.Mask" "F.Paste")
			(net "GND")
		)
		(pad "C8" smd circle
			(at -0.40005 -4.400042 180)
			(size 0.4064 0.4064)
			(layers "F.Cu" "F.Mask" "F.Paste")
			(net "BIC_FWSPIMISO")
		)
		(pad "C9" smd circle
			(at 0.40005 -4.400042 180)
			(size 0.4064 0.4064)
			(layers "F.Cu" "F.Mask" "F.Paste")
			(net "BIC_SEL_FLASH_SW1")
		)
		(pad "C10" smd circle
			(at 1.199896 -4.400042 180)
			(size 0.4064 0.4064)
			(layers "F.Cu" "F.Mask" "F.Paste")
			(net "JTAG_BIC_TDI")
		)
		(pad "C11" smd circle
			(at 1.999996 -4.400042 180)
			(size 0.4064 0.4064)
			(layers "F.Cu" "F.Mask" "F.Paste")
			(net "RST_SMB_FIO_N")
		)
		(pad "C12" smd circle
			(at 2.800096 -4.400042 180)
			(size 0.4064 0.4064)
			(layers "F.Cu" "F.Mask" "F.Paste")
			(net "JTAG_BIC_EN")
		)
		(pad "C13" smd circle
			(at 3.599942 -4.400042 180)
			(size 0.4064 0.4064)
			(layers "F.Cu" "F.Mask" "F.Paste")
			(net "FM_SYS_THROTTLE_R1")
		)
		(pad "C14" smd circle
			(at 4.400042 -4.400042 180)
			(size 0.4064 0.4064)
			(layers "F.Cu" "F.Mask" "F.Paste")
			(net "IRQ_SSD_LED_IOEXP_R_N")
		)
		(pad "C15" smd circle
			(at 5.199888 -4.400042 180)
			(size 0.4064 0.4064)
			(layers "F.Cu" "F.Mask" "F.Paste")
			(net "RST_BIC_I2C9_SSD_MUX0_N")
		)
		(pad "C16" smd circle
			(at 5.999988 -4.400042 180)
			(size 0.4064 0.4064)
			(layers "F.Cu" "F.Mask" "F.Paste")
			(net "SSD_8_15_ADC_ALERT_N")
		)
		(pad "D1" smd circle
			(at -5.999988 -3.599942 180)
			(size 0.4064 0.4064)
			(layers "F.Cu" "F.Mask" "F.Paste")
			(net "P1V8_PLL0_PEX0_SCALED")
		)
		(pad "D2" smd circle
			(at -5.199888 -3.599942 180)
			(size 0.4064 0.4064)
			(layers "F.Cu" "F.Mask" "F.Paste")
			(net "P1V8_PLL0_PEX1_SCALED")
		)
		(pad "D3" smd circle
			(at -4.400042 -3.599942 180)
			(size 0.4064 0.4064)
			(layers "F.Cu" "F.Mask" "F.Paste")
			(net "P1V2_AUX_SCALED")
		)
		(pad "D4" smd circle
			(at -3.599942 -3.599942 180)
			(size 0.4064 0.4064)
			(layers "F.Cu" "F.Mask" "F.Paste")
			(net "CLK_25M_BIC_CLKIN")
		)
		(pad "D5" smd circle
			(at -2.800096 -3.599942 180)
			(size 0.4064 0.4064)
			(layers "F.Cu" "F.Mask" "F.Paste")
			(net "BIC_FWSPIDQ3")
		)
		(pad "D6" smd circle
			(at -1.999996 -3.599942 180)
			(size 0.4064 0.4064)
			(layers "F.Cu" "F.Mask" "F.Paste")
			(net "GND")
		)
		(pad "D7" smd circle
			(at -1.199896 -3.599942 180)
			(size 0.4064 0.4064)
			(layers "F.Cu" "F.Mask" "F.Paste")
			(net "GND")
		)
		(pad "D8" smd circle
			(at -0.40005 -3.599942 180)
			(size 0.4064 0.4064)
			(layers "F.Cu" "F.Mask" "F.Paste")
			(net "BIC_FWSPIDQ2")
		)
		(pad "D9" smd circle
			(at 0.40005 -3.599942 180)
			(size 0.4064 0.4064)
			(layers "F.Cu" "F.Mask" "F.Paste")
			(net "BIC_SEL_FLASH_SW2")
		)
		(pad "D10" smd circle
			(at 1.199896 -3.599942 180)
			(size 0.4064 0.4064)
			(layers "F.Cu" "F.Mask" "F.Paste")
			(net "JTAG_BIC_TCK")
		)
		(pad "D11" smd circle
			(at 1.999996 -3.599942 180)
			(size 0.4064 0.4064)
			(layers "F.Cu" "F.Mask" "F.Paste")
			(net "MB_BIC_MON")
		)
		(pad "D12" smd circle
			(at 2.800096 -3.599942 180)
			(size 0.4064 0.4064)
			(layers "F.Cu" "F.Mask" "F.Paste")
			(net "SGPIO_BIC_DOUT")
		)
		(pad "D13" smd circle
			(at 3.599942 -3.599942 180)
			(size 0.4064 0.4064)
			(layers "F.Cu" "F.Mask" "F.Paste")
			(net "UART_BIC_DEBUG_TX")
		)
		(pad "D14" smd circle
			(at 4.400042 -3.599942 180)
			(size 0.4064 0.4064)
			(layers "F.Cu" "F.Mask" "F.Paste")
			(net "RST_BIC_USB_HUB_N")
		)
		(pad "D15" smd circle
			(at 5.199888 -3.599942 180)
			(size 0.4064 0.4064)
			(layers "F.Cu" "F.Mask" "F.Paste")
			(net "NIC_ADC_ALERT_N")
		)
		(pad "D16" smd circle
			(at 5.999988 -3.599942 180)
			(size 0.4064 0.4064)
			(layers "F.Cu" "F.Mask" "F.Paste")
			(net "SSD_0_7_ADC_ALERT_N")
		)
		(pad "E1" smd circle
			(at -5.999988 -2.800096 180)
			(size 0.4064 0.4064)
			(layers "F.Cu" "F.Mask" "F.Paste")
			(net "BIC_ADCVREFN0")
		)
		(pad "E2" smd circle
			(at -5.199888 -2.800096 180)
			(size 0.4064 0.4064)
			(layers "F.Cu" "F.Mask" "F.Paste")
			(net "BIC_ADCVREFP0")
		)
		(pad "E3" smd circle
			(at -4.400042 -2.800096 180)
			(size 0.4064 0.4064)
			(layers "F.Cu" "F.Mask" "F.Paste")
			(net "GND")
		)
		(pad "E4" smd circle
			(at -3.599942 -2.800096 180)
			(size 0.4064 0.4064)
			(layers "F.Cu" "F.Mask" "F.Paste")
			(net "USB2_BIC_DP")
		)
		(pad "E5" smd circle
			(at -2.800096 -2.800096 180)
			(size 0.4064 0.4064)
			(layers "F.Cu" "F.Mask" "F.Paste")
			(net "P1V2_BIC_USB2AV12")
		)
		(pad "E6" smd circle
			(at -1.999996 -2.800096 180)
			(size 0.4064 0.4064)
			(layers "F.Cu" "F.Mask" "F.Paste")
			(net "GND")
		)
		(pad "E7" smd circle
			(at -1.199896 -2.800096 180)
			(size 0.4064 0.4064)
			(layers "F.Cu" "F.Mask" "F.Paste")
			(net "BIC_FWSPICK")
		)
		(pad "E8" smd circle
			(at -0.40005 -2.800096 180)
			(size 0.4064 0.4064)
			(layers "F.Cu" "F.Mask" "F.Paste")
			(net "P3V3_AUX")
		)
		(pad "E9" smd circle
			(at 0.40005 -2.800096 180)
			(size 0.4064 0.4064)
			(layers "F.Cu" "F.Mask" "F.Paste")
			(net "P3V3_AUX")
		)
		(pad "E10" smd circle
			(at 1.199896 -2.800096 180)
			(size 0.4064 0.4064)
			(layers "F.Cu" "F.Mask" "F.Paste")
			(net "P3V3_AUX")
		)
		(pad "E11" smd circle
			(at 1.999996 -2.800096 180)
			(size 0.4064 0.4064)
			(layers "F.Cu" "F.Mask" "F.Paste")
			(net "RST_PEX_USB_HUB_N")
		)
		(pad "E12" smd circle
			(at 2.800096 -2.800096 180)
			(size 0.4064 0.4064)
			(layers "F.Cu" "F.Mask" "F.Paste")
			(net "Net_589")
		)
		(pad "E13" smd circle
			(at 3.599942 -2.800096 180)
			(size 0.4064 0.4064)
			(layers "F.Cu" "F.Mask" "F.Paste")
			(net "RST_BIC_SELF_HW_RST_N")
		)
		(pad "E14" smd circle
			(at 4.400042 -2.800096 180)
			(size 0.4064 0.4064)
			(layers "F.Cu" "F.Mask" "F.Paste")
			(net "PRSNT_GPU_ISO_R_N")
		)
		(pad "E15" smd circle
			(at 5.199888 -2.800096 180)
			(size 0.4064 0.4064)
			(layers "F.Cu" "F.Mask" "F.Paste")
			(net "Net_640")
		)
		(pad "E16" smd circle
			(at 5.999988 -2.800096 180)
			(size 0.4064 0.4064)
			(layers "F.Cu" "F.Mask" "F.Paste")
			(net "RST_MB_BMC_N")
		)
		(pad "F1" smd circle
			(at -5.999988 -1.999996 180)
			(size 0.4064 0.4064)
			(layers "F.Cu" "F.Mask" "F.Paste")
			(net "PD_BIC_ADCREXT0")
		)
		(pad "F2" smd circle
			(at -5.199888 -1.999996 180)
			(size 0.4064 0.4064)
			(layers "F.Cu" "F.Mask" "F.Paste")
			(net "P1V2_BIC_ADCVREFREXT0")
		)
		(pad "F3" smd circle
			(at -4.400042 -1.999996 180)
			(size 0.4064 0.4064)
			(layers "F.Cu" "F.Mask" "F.Paste")
			(net "GND")
		)
		(pad "F4" smd circle
			(at -3.599942 -1.999996 180)
			(size 0.4064 0.4064)
			(layers "F.Cu" "F.Mask" "F.Paste")
			(net "USB2_BIC_DN")
		)
		(pad "F5" smd circle
			(at -2.800096 -1.999996 180)
			(size 0.4064 0.4064)
			(layers "F.Cu" "F.Mask" "F.Paste")
			(net "P3V3_BIC_USB2AV33")
		)
		(pad "F6" smd circle
			(at -1.999996 -1.999996 180)
			(size 0.4064 0.4064)
			(layers "F.Cu" "F.Mask" "F.Paste")
			(net "GND")
		)
		(pad "F7" smd circle
			(at -1.199896 -1.999996 180)
			(size 0.4064 0.4064)
			(layers "F.Cu" "F.Mask" "F.Paste")
			(net "BIC_FWSPICS1_N")
		)
		(pad "F8" smd circle
			(at -0.40005 -1.999996 180)
			(size 0.4064 0.4064)
			(layers "F.Cu" "F.Mask" "F.Paste")
			(net "P1V2_AUX")
		)
		(pad "F9" smd circle
			(at 0.40005 -1.999996 180)
			(size 0.4064 0.4064)
			(layers "F.Cu" "F.Mask" "F.Paste")
			(net "P1V2_AUX")
		)
		(pad "F10" smd circle
			(at 1.199896 -1.999996 180)
			(size 0.4064 0.4064)
			(layers "F.Cu" "F.Mask" "F.Paste")
			(net "P1V2_AUX")
		)
		(pad "F11" smd circle
			(at 1.999996 -1.999996 180)
			(size 0.4064 0.4064)
			(layers "F.Cu" "F.Mask" "F.Paste")
			(net "RST_BIC_I2C6_MUX_N")
		)
		(pad "F12" smd circle
			(at 2.800096 -1.999996 180)
			(size 0.4064 0.4064)
			(layers "F.Cu" "F.Mask" "F.Paste")
			(net "BIC_UART_BIC_SEL")
		)
		(pad "F13" smd circle
			(at 3.599942 -1.999996 180)
			(size 0.4064 0.4064)
			(layers "F.Cu" "F.Mask" "F.Paste")
			(net "P3V3_AUX")
		)
		(pad "F14" smd circle
			(at 4.400042 -1.999996 180)
			(size 0.4064 0.4064)
			(layers "F.Cu" "F.Mask" "F.Paste")
			(net "SMB_ALERT_HSC_R_N")
		)
		(pad "F15" smd circle
			(at 5.199888 -1.999996 180)
			(size 0.4064 0.4064)
			(layers "F.Cu" "F.Mask" "F.Paste")
			(net "USB_DEBUG_RST_BTN_R_N")
		)
		(pad "F16" smd circle
			(at 5.999988 -1.999996 180)
			(size 0.4064 0.4064)
			(layers "F.Cu" "F.Mask" "F.Paste")
			(net "SMB_ALERT_PMBUS_R_N")
		)
		(pad "G1" smd circle
			(at -5.999988 -1.199896 180)
			(size 0.4064 0.4064)
			(layers "F.Cu" "F.Mask" "F.Paste")
			(net "P1V2_BIC_ADCVREFREXT1")
		)
		(pad "G2" smd circle
			(at -5.199888 -1.199896 180)
			(size 0.4064 0.4064)
			(layers "F.Cu" "F.Mask" "F.Paste")
			(net "PD_BIC_ADCREXT1")
		)
		(pad "G3" smd circle
			(at -4.400042 -1.199896 180)
			(size 0.4064 0.4064)
			(layers "F.Cu" "F.Mask" "F.Paste")
			(net "P1V2_BIC_PLL")
		)
		(pad "G4" smd circle
			(at -3.599942 -1.199896 180)
			(size 0.4064 0.4064)
			(layers "F.Cu" "F.Mask" "F.Paste")
			(net "P3V3_AUX")
		)
		(pad "G5" smd circle
			(at -2.800096 -1.199896 180)
			(size 0.4064 0.4064)
			(layers "F.Cu" "F.Mask" "F.Paste")
			(net "P1V2_AUX")
		)
		(pad "G6" smd circle
			(at -1.999996 -1.199896 180)
			(size 0.4064 0.4064)
			(layers "F.Cu" "F.Mask" "F.Paste")
			(net "GND")
		)
		(pad "G7" smd circle
			(at -1.199896 -1.199896 180)
			(size 0.4064 0.4064)
			(layers "F.Cu" "F.Mask" "F.Paste")
			(net "GND")
		)
		(pad "G8" smd circle
			(at -0.40005 -1.199896 180)
			(size 0.4064 0.4064)
			(layers "F.Cu" "F.Mask" "F.Paste")
			(net "GND")
		)
		(pad "G9" smd circle
			(at 0.40005 -1.199896 180)
			(size 0.4064 0.4064)
			(layers "F.Cu" "F.Mask" "F.Paste")
			(net "GND")
		)
		(pad "G10" smd circle
			(at 1.199896 -1.199896 180)
			(size 0.4064 0.4064)
			(layers "F.Cu" "F.Mask" "F.Paste")
			(net "GND")
		)
		(pad "G11" smd circle
			(at 1.999996 -1.199896 180)
			(size 0.4064 0.4064)
			(layers "F.Cu" "F.Mask" "F.Paste")
			(net "GND")
		)
		(pad "G12" smd circle
			(at 2.800096 -1.199896 180)
			(size 0.4064 0.4064)
			(layers "F.Cu" "F.Mask" "F.Paste")
			(net "P3V3_AUX")
		)
		(pad "G13" smd circle
			(at 3.599942 -1.199896 180)
			(size 0.4064 0.4064)
			(layers "F.Cu" "F.Mask" "F.Paste")
			(net "P3V3_AUX")
		)
		(pad "G14" smd circle
			(at 4.400042 -1.199896 180)
			(size 0.4064 0.4064)
			(layers "F.Cu" "F.Mask" "F.Paste")
			(net "SMB_FPGA_ALERT_R_N")
		)
	)
)
